(kicad_pcb
	(version 20260206)
	(generator "pcbnew")
	(generator_version "10.0")
	(general
		(thickness 1.6)
		(legacy_teardrops no)
	)
	(paper "A4")
	(title_block
		(title "01162023_DA0F0TEBIF0_F0T_Expander_BD_F_brd_V02_OCP.brd")
		(comment 1 "Grand Teton / footprints 7596-7605 of 9728")
	)
	(layers
		(0 "F.Cu" signal "TOP")
		(4 "In1.Cu" signal "GND")
		(6 "In2.Cu" signal "VCC")
		(8 "In3.Cu" signal "VCC1")
		(10 "In4.Cu" signal "GND1")
		(12 "In5.Cu" signal "IN1")
		(14 "In6.Cu" signal "GND2")
		(16 "In7.Cu" signal "IN2")
		(18 "In8.Cu" signal "GND3")
		(20 "In9.Cu" signal "IN3")
		(22 "In10.Cu" signal "GND4")
		(24 "In11.Cu" signal "IN4")
		(26 "In12.Cu" signal "GND5")
		(28 "In13.Cu" signal "IN5")
		(30 "In14.Cu" signal "GND6")
		(32 "In15.Cu" signal "IN6")
		(34 "In16.Cu" signal "GND7")
		(2 "B.Cu" signal "BOTTOM")
		(9 "F.Adhes" user "F.Adhesive")
		(11 "B.Adhes" user "B.Adhesive")
		(13 "F.Paste" user "Package Geometry/Pastemask Top")
		(15 "B.Paste" user "Package Geometry/Pastemask Bottom")
		(5 "F.SilkS" user "Ref Des/Silkscreen Top")
		(7 "B.SilkS" user "Ref Des/Silkscreen Bottom")
		(1 "F.Mask" user "Board Geometry/Soldermask Top")
		(3 "B.Mask" user "Board Geometry/Soldermask Bottom")
		(17 "Dwgs.User" user "User.Drawings")
		(19 "Cmts.User" user "User.Comments")
		(21 "Eco1.User" user "User.Eco1")
		(23 "Eco2.User" user "User.Eco2")
		(25 "Edge.Cuts" user "Board Geometry/Outline")
		(27 "Margin" user)
		(31 "F.CrtYd" user "Package Geometry/Place Bound Top")
		(29 "B.CrtYd" user "Package Geometry/Place Bound Bottom")
		(35 "F.Fab" user "Ref Des/Assembly Top")
		(33 "B.Fab" user "Ref Des/Assembly Bottom")
	)
	(footprint ""
		(layer "B.Cu")
		(at 130.25882 -319.545462 -90)
		(property "Reference" "L30"
			(at 0 0 90)
			(layer "B.SilkS")
			(hide yes)
			(effects
				(font
					(size 1.27 1.27)
				)
				(justify mirror)
			)
		)
		(property "Value" ""
			(at 0 0 90)
			(layer "B.Fab")
			(effects
				(font
					(size 1.27 1.27)
				)
				(justify mirror)
			)
		)
		(duplicate_pad_numbers_are_jumpers no)
		(fp_line
			(start 2.248154 4.9911)
			(end -2.248154 4.9911)
			(stroke
				(width 0.1524)
				(type default)
			)
			(layer "B.SilkS")
		)
		(fp_line
			(start 2.248154 1.846834)
			(end 2.248154 4.9911)
			(stroke
				(width 0.1524)
				(type default)
			)
			(layer "B.SilkS")
		)
		(fp_line
			(start -2.248154 -4.9911)
			(end 2.248154 -4.9911)
			(stroke
				(width 0.1524)
				(type default)
			)
			(layer "B.SilkS")
		)
		(fp_line
			(start 2.248154 -4.9911)
			(end 2.248154 -2.276348)
			(stroke
				(width 0.1524)
				(type default)
			)
			(layer "B.SilkS")
		)
		(fp_line
			(start -1.700022 0.899922)
			(end -1.700022 -0.899922)
			(stroke
				(width 0.1)
				(type default)
			)
			(layer "B.Fab")
		)
		(fp_line
			(start 1.700022 0.899922)
			(end -1.700022 0.899922)
			(stroke
				(width 0.1)
				(type default)
			)
			(layer "B.Fab")
		)
		(fp_line
			(start -1.700022 -0.899922)
			(end 1.700022 -0.899922)
			(stroke
				(width 0.1)
				(type default)
			)
			(layer "B.Fab")
		)
		(fp_line
			(start 1.700022 -0.899922)
			(end 1.700022 0.899922)
			(stroke
				(width 0.1)
				(type default)
			)
			(layer "B.Fab")
		)
		(pad "1" smd rect
			(at 1.575054 0 90)
			(size 1.1684 9.8044)
			(layers "B.Cu" "B.Mask" "B.Paste")
			(net "P0V8_PEX1")
		)
		(pad "2" smd rect
			(at -1.575054 0 90)
			(size 1.1684 9.8044)
			(layers "B.Cu" "B.Mask" "B.Paste")
			(net "P0V8_SERDES_VDDA_PEX1")
		)
	)
	(footprint ""
		(layer "B.Cu")
		(at 400.349974 -288.299906 90)
		(property "Reference" "C3450"
			(at 0 0 90)
			(layer "B.SilkS")
			(hide yes)
			(effects
				(font
					(size 1.27 1.27)
				)
				(justify mirror)
			)
		)
		(property "Value" ""
			(at 0 0 90)
			(layer "B.Fab")
			(effects
				(font
					(size 1.27 1.27)
				)
				(justify mirror)
			)
		)
		(duplicate_pad_numbers_are_jumpers no)
		(fp_line
			(start 0.299974 -0.150114)
			(end -0.299974 -0.150114)
			(stroke
				(width 0.1)
				(type default)
			)
			(layer "B.Fab")
		)
		(fp_line
			(start -0.299974 -0.150114)
			(end -0.299974 0.150114)
			(stroke
				(width 0.1)
				(type default)
			)
			(layer "B.Fab")
		)
		(fp_line
			(start 0.299974 0.150114)
			(end 0.299974 -0.150114)
			(stroke
				(width 0.1)
				(type default)
			)
			(layer "B.Fab")
		)
		(fp_line
			(start -0.299974 0.150114)
			(end 0.299974 0.150114)
			(stroke
				(width 0.1)
				(type default)
			)
			(layer "B.Fab")
		)
		(pad "1" smd rect
			(at 0.2667 0 270)
			(size 0.3048 0.381)
			(layers "B.Cu" "B.Mask" "B.Paste")
			(net "P1V25_PEX3")
		)
		(pad "2" smd rect
			(at -0.2667 0 270)
			(size 0.3048 0.381)
			(layers "B.Cu" "B.Mask" "B.Paste")
			(net "GND")
		)
	)
	(footprint ""
		(layer "B.Cu")
		(at 286.624776 -286.399732 90)
		(property "Reference" "C3332"
			(at 0 0 90)
			(layer "B.SilkS")
			(hide yes)
			(effects
				(font
					(size 1.27 1.27)
				)
				(justify mirror)
			)
		)
		(property "Value" ""
			(at 0 0 90)
			(layer "B.Fab")
			(effects
				(font
					(size 1.27 1.27)
				)
				(justify mirror)
			)
		)
		(duplicate_pad_numbers_are_jumpers no)
		(fp_line
			(start 0.299974 -0.150114)
			(end -0.299974 -0.150114)
			(stroke
				(width 0.1)
				(type default)
			)
			(layer "B.Fab")
		)
		(fp_line
			(start -0.299974 -0.150114)
			(end -0.299974 0.150114)
			(stroke
				(width 0.1)
				(type default)
			)
			(layer "B.Fab")
		)
		(fp_line
			(start 0.299974 0.150114)
			(end 0.299974 -0.150114)
			(stroke
				(width 0.1)
				(type default)
			)
			(layer "B.Fab")
		)
		(fp_line
			(start -0.299974 0.150114)
			(end 0.299974 0.150114)
			(stroke
				(width 0.1)
				(type default)
			)
			(layer "B.Fab")
		)
		(pad "1" smd rect
			(at 0.2667 0 270)
			(size 0.3048 0.381)
			(layers "B.Cu" "B.Mask" "B.Paste")
			(net "P1V25_SERDES_VDDPLL_PEX2")
		)
		(pad "2" smd rect
			(at -0.2667 0 270)
			(size 0.3048 0.381)
			(layers "B.Cu" "B.Mask" "B.Paste")
			(net "GND")
		)
	)
	(footprint ""
		(layer "B.Cu")
		(at 292.79977 -290.199826 90)
		(property "Reference" "C1707"
			(at 0 0 90)
			(layer "B.SilkS")
			(hide yes)
			(effects
				(font
					(size 1.27 1.27)
				)
				(justify mirror)
			)
		)
		(property "Value" ""
			(at 0 0 90)
			(layer "B.Fab")
			(effects
				(font
					(size 1.27 1.27)
				)
				(justify mirror)
			)
		)
		(duplicate_pad_numbers_are_jumpers no)
		(fp_line
			(start 0.299974 -0.150114)
			(end -0.299974 -0.150114)
			(stroke
				(width 0.1)
				(type default)
			)
			(layer "B.Fab")
		)
		(fp_line
			(start -0.299974 -0.150114)
			(end -0.299974 0.150114)
			(stroke
				(width 0.1)
				(type default)
			)
			(layer "B.Fab")
		)
		(fp_line
			(start 0.299974 0.150114)
			(end 0.299974 -0.150114)
			(stroke
				(width 0.1)
				(type default)
			)
			(layer "B.Fab")
		)
		(fp_line
			(start -0.299974 0.150114)
			(end 0.299974 0.150114)
			(stroke
				(width 0.1)
				(type default)
			)
			(layer "B.Fab")
		)
		(pad "1" smd rect
			(at 0.2667 0 270)
			(size 0.3048 0.381)
			(layers "B.Cu" "B.Mask" "B.Paste")
			(net "P0V8_SERDES_VDDA_PEX2")
		)
		(pad "2" smd rect
			(at -0.2667 0 270)
			(size 0.3048 0.381)
			(layers "B.Cu" "B.Mask" "B.Paste")
			(net "GND")
		)
	)
	(footprint ""
		(layer "B.Cu")
		(at 349.135954 -260.400546 -90)
		(property "Reference" "PC135"
			(at 0 0 90)
			(layer "B.SilkS")
			(hide yes)
			(effects
				(font
					(size 1.27 1.27)
				)
				(justify mirror)
			)
		)
		(property "Value" ""
			(at 0 0 90)
			(layer "B.Fab")
			(effects
				(font
					(size 1.27 1.27)
				)
				(justify mirror)
			)
		)
		(duplicate_pad_numbers_are_jumpers no)
		(fp_line
			(start -0.7874 0.4064)
			(end 0.7874 0.4064)
			(stroke
				(width 0.1524)
				(type default)
			)
			(layer "B.SilkS")
		)
		(fp_line
			(start 0.7874 0.4064)
			(end 0.7874 -0.4064)
			(stroke
				(width 0.1524)
				(type default)
			)
			(layer "B.SilkS")
		)
		(fp_line
			(start -0.7874 -0.4064)
			(end -0.7874 0.4064)
			(stroke
				(width 0.1524)
				(type default)
			)
			(layer "B.SilkS")
		)
		(fp_line
			(start 0.7874 -0.4064)
			(end -0.7874 -0.4064)
			(stroke
				(width 0.1524)
				(type default)
			)
			(layer "B.SilkS")
		)
		(fp_line
			(start -0.67945 0.3048)
			(end -0.120396 0.3048)
			(stroke
				(width 0.1)
				(type default)
			)
			(layer "B.Fab")
		)
		(fp_line
			(start -0.120396 0.3048)
			(end -0.120396 0.2794)
			(stroke
				(width 0.1)
				(type default)
			)
			(layer "B.Fab")
		)
		(fp_line
			(start 0.12065 0.3048)
			(end 0.67945 0.3048)
			(stroke
				(width 0.1)
				(type default)
			)
			(layer "B.Fab")
		)
		(fp_line
			(start 0.67945 0.3048)
			(end 0.67945 -0.305054)
			(stroke
				(width 0.1)
				(type default)
			)
			(layer "B.Fab")
		)
		(fp_line
			(start -0.120396 0.2794)
			(end 0.12065 0.2794)
			(stroke
				(width 0.1)
				(type default)
			)
			(layer "B.Fab")
		)
		(fp_line
			(start 0.12065 0.2794)
			(end 0.12065 0.3048)
			(stroke
				(width 0.1)
				(type default)
			)
			(layer "B.Fab")
		)
		(fp_line
			(start -0.12065 -0.2794)
			(end -0.12065 -0.3048)
			(stroke
				(width 0.1)
				(type default)
			)
			(layer "B.Fab")
		)
		(fp_line
			(start 0.12065 -0.2794)
			(end -0.12065 -0.2794)
			(stroke
				(width 0.1)
				(type default)
			)
			(layer "B.Fab")
		)
		(fp_line
			(start -0.67945 -0.3048)
			(end -0.67945 0.3048)
			(stroke
				(width 0.1)
				(type default)
			)
			(layer "B.Fab")
		)
		(fp_line
			(start -0.12065 -0.3048)
			(end -0.67945 -0.3048)
			(stroke
				(width 0.1)
				(type default)
			)
			(layer "B.Fab")
		)
		(fp_line
			(start 0.12065 -0.305054)
			(end 0.12065 -0.2794)
			(stroke
				(width 0.1)
				(type default)
			)
			(layer "B.Fab")
		)
		(fp_line
			(start 0.67945 -0.305054)
			(end 0.12065 -0.305054)
			(stroke
				(width 0.1)
				(type default)
			)
			(layer "B.Fab")
		)
		(pad "1" smd circle
			(at 0.40005 0 90)
			(size 0 0)
			(layers "B.Cu" "B.Mask" "B.Paste")
			(net "P0V8_PEX2_TSEN_R")
		)
		(pad "2" smd circle
			(at -0.40005 0 90)
			(size 0 0)
			(layers "B.Cu" "B.Mask" "B.Paste")
			(net "GND")
		)
	)
	(footprint ""
		(layer "B.Cu")
		(at 122.96521 -260.469126 90)
		(property "Reference" "PR7134"
			(at 0 0 90)
			(layer "B.SilkS")
			(hide yes)
			(effects
				(font
					(size 1.27 1.27)
				)
				(justify mirror)
			)
		)
		(property "Value" ""
			(at 0 0 90)
			(layer "B.Fab")
			(effects
				(font
					(size 1.27 1.27)
				)
				(justify mirror)
			)
		)
		(duplicate_pad_numbers_are_jumpers no)
		(fp_line
			(start 0.7874 -0.4064)
			(end -0.7874 -0.4064)
			(stroke
				(width 0.1524)
				(type default)
			)
			(layer "B.SilkS")
		)
		(fp_line
			(start -0.7874 -0.4064)
			(end -0.7874 0.4064)
			(stroke
				(width 0.1524)
				(type default)
			)
			(layer "B.SilkS")
		)
		(fp_line
			(start 0.7874 0.4064)
			(end 0.7874 -0.4064)
			(stroke
				(width 0.1524)
				(type default)
			)
			(layer "B.SilkS")
		)
		(fp_line
			(start -0.7874 0.4064)
			(end 0.7874 0.4064)
			(stroke
				(width 0.1524)
				(type default)
			)
			(layer "B.SilkS")
		)
		(fp_line
			(start 0.67945 -0.305054)
			(end 0.12065 -0.305054)
			(stroke
				(width 0.1)
				(type default)
			)
			(layer "B.Fab")
		)
		(fp_line
			(start 0.12065 -0.305054)
			(end 0.12065 -0.2794)
			(stroke
				(width 0.1)
				(type default)
			)
			(layer "B.Fab")
		)
		(fp_line
			(start -0.12065 -0.3048)
			(end -0.67945 -0.3048)
			(stroke
				(width 0.1)
				(type default)
			)
			(layer "B.Fab")
		)
		(fp_line
			(start -0.67945 -0.3048)
			(end -0.67945 0.3048)
			(stroke
				(width 0.1)
				(type default)
			)
			(layer "B.Fab")
		)
		(fp_line
			(start 0.12065 -0.2794)
			(end -0.12065 -0.2794)
			(stroke
				(width 0.1)
				(type default)
			)
			(layer "B.Fab")
		)
		(fp_line
			(start -0.12065 -0.2794)
			(end -0.12065 -0.3048)
			(stroke
				(width 0.1)
				(type default)
			)
			(layer "B.Fab")
		)
		(fp_line
			(start 0.12065 0.2794)
			(end 0.12065 0.3048)
			(stroke
				(width 0.1)
				(type default)
			)
			(layer "B.Fab")
		)
		(fp_line
			(start -0.120396 0.2794)
			(end 0.12065 0.2794)
			(stroke
				(width 0.1)
				(type default)
			)
			(layer "B.Fab")
		)
		(fp_line
			(start 0.67945 0.3048)
			(end 0.67945 -0.305054)
			(stroke
				(width 0.1)
				(type default)
			)
			(layer "B.Fab")
		)
		(fp_line
			(start 0.12065 0.3048)
			(end 0.67945 0.3048)
			(stroke
				(width 0.1)
				(type default)
			)
			(layer "B.Fab")
		)
		(fp_line
			(start -0.120396 0.3048)
			(end -0.120396 0.2794)
			(stroke
				(width 0.1)
				(type default)
			)
			(layer "B.Fab")
		)
		(fp_line
			(start -0.67945 0.3048)
			(end -0.120396 0.3048)
			(stroke
				(width 0.1)
				(type default)
			)
			(layer "B.Fab")
		)
		(pad "1" smd circle
			(at 0.40005 0 270)
			(size 0 0)
			(layers "B.Cu" "B.Mask" "B.Paste")
			(net "NC_P0V8_PEX0_ISEN3")
		)
		(pad "2" smd circle
			(at -0.40005 0 270)
			(size 0 0)
			(layers "B.Cu" "B.Mask" "B.Paste")
			(net "GND")
		)
	)
	(footprint ""
		(layer "B.Cu")
		(at 165.508178 -303.024794 180)
		(property "Reference" "C3184"
			(at 0 0 0)
			(layer "B.SilkS")
			(hide yes)
			(effects
				(font
					(size 1.27 1.27)
				)
				(justify mirror)
			)
		)
		(property "Value" ""
			(at 0 0 0)
			(layer "B.Fab")
			(effects
				(font
					(size 1.27 1.27)
				)
				(justify mirror)
			)
		)
		(duplicate_pad_numbers_are_jumpers no)
		(fp_line
			(start 0.299974 0.150114)
			(end 0.299974 -0.150114)
			(stroke
				(width 0.1)
				(type default)
			)
			(layer "B.Fab")
		)
		(fp_line
			(start 0.299974 -0.150114)
			(end -0.299974 -0.150114)
			(stroke
				(width 0.1)
				(type default)
			)
			(layer "B.Fab")
		)
		(fp_line
			(start -0.299974 0.150114)
			(end 0.299974 0.150114)
			(stroke
				(width 0.1)
				(type default)
			)
			(layer "B.Fab")
		)
		(fp_line
			(start -0.299974 -0.150114)
			(end -0.299974 0.150114)
			(stroke
				(width 0.1)
				(type default)
			)
			(layer "B.Fab")
		)
		(pad "1" smd rect
			(at 0.2667 0)
			(size 0.3048 0.381)
			(layers "B.Cu" "B.Mask" "B.Paste")
			(net "P1V8_VDDA_PEX1")
		)
		(pad "2" smd rect
			(at -0.2667 0)
			(size 0.3048 0.381)
			(layers "B.Cu" "B.Mask" "B.Paste")
			(net "GND")
		)
	)
	(footprint ""
		(layer "B.Cu")
		(at 356.918006 -282.166822 90)
		(property "Reference" "R6768"
			(at 0 0 90)
			(layer "B.SilkS")
			(hide yes)
			(effects
				(font
					(size 1.27 1.27)
				)
				(justify mirror)
			)
		)
		(property "Value" ""
			(at 0 0 90)
			(layer "B.Fab")
			(effects
				(font
					(size 1.27 1.27)
				)
				(justify mirror)
			)
		)
		(duplicate_pad_numbers_are_jumpers no)
		(fp_line
			(start 0.7874 -0.4064)
			(end -0.7874 -0.4064)
			(stroke
				(width 0.1524)
				(type default)
			)
			(layer "B.SilkS")
		)
		(fp_line
			(start -0.7874 -0.4064)
			(end -0.7874 0.4064)
			(stroke
				(width 0.1524)
				(type default)
			)
			(layer "B.SilkS")
		)
		(fp_line
			(start 0.7874 0.4064)
			(end 0.7874 -0.4064)
			(stroke
				(width 0.1524)
				(type default)
			)
			(layer "B.SilkS")
		)
		(fp_line
			(start -0.7874 0.4064)
			(end 0.7874 0.4064)
			(stroke
				(width 0.1524)
				(type default)
			)
			(layer "B.SilkS")
		)
		(fp_line
			(start 0.67945 -0.305054)
			(end 0.12065 -0.305054)
			(stroke
				(width 0.1)
				(type default)
			)
			(layer "B.Fab")
		)
		(fp_line
			(start 0.12065 -0.305054)
			(end 0.12065 -0.2794)
			(stroke
				(width 0.1)
				(type default)
			)
			(layer "B.Fab")
		)
		(fp_line
			(start -0.12065 -0.3048)
			(end -0.67945 -0.3048)
			(stroke
				(width 0.1)
				(type default)
			)
			(layer "B.Fab")
		)
		(fp_line
			(start -0.67945 -0.3048)
			(end -0.67945 0.3048)
			(stroke
				(width 0.1)
				(type default)
			)
			(layer "B.Fab")
		)
		(fp_line
			(start 0.12065 -0.2794)
			(end -0.12065 -0.2794)
			(stroke
				(width 0.1)
				(type default)
			)
			(layer "B.Fab")
		)
		(fp_line
			(start -0.12065 -0.2794)
			(end -0.12065 -0.3048)
			(stroke
				(width 0.1)
				(type default)
			)
			(layer "B.Fab")
		)
		(fp_line
			(start 0.12065 0.2794)
			(end 0.12065 0.3048)
			(stroke
				(width 0.1)
				(type default)
			)
			(layer "B.Fab")
		)
		(fp_line
			(start -0.120396 0.2794)
			(end 0.12065 0.2794)
			(stroke
				(width 0.1)
				(type default)
			)
			(layer "B.Fab")
		)
		(fp_line
			(start 0.67945 0.3048)
			(end 0.67945 -0.305054)
			(stroke
				(width 0.1)
				(type default)
			)
			(layer "B.Fab")
		)
		(fp_line
			(start 0.12065 0.3048)
			(end 0.67945 0.3048)
			(stroke
				(width 0.1)
				(type default)
			)
			(layer "B.Fab")
		)
		(fp_line
			(start -0.120396 0.3048)
			(end -0.120396 0.2794)
			(stroke
				(width 0.1)
				(type default)
			)
			(layer "B.Fab")
		)
		(fp_line
			(start -0.67945 0.3048)
			(end -0.120396 0.3048)
			(stroke
				(width 0.1)
				(type default)
			)
			(layer "B.Fab")
		)
		(pad "1" smd circle
			(at 0.40005 0 270)
			(size 0 0)
			(layers "B.Cu" "B.Mask" "B.Paste")
			(net "P0V8_PEX3_VCC1")
		)
		(pad "2" smd circle
			(at -0.40005 0 270)
			(size 0 0)
			(layers "B.Cu" "B.Mask" "B.Paste")
			(net "P0V8_PEX2_EN3")
		)
	)
	(footprint ""
		(layer "B.Cu")
		(at 278.554942 -300.1772)
		(property "Reference" "C3373"
			(at 0 0 0)
			(layer "B.SilkS")
			(hide yes)
			(effects
				(font
					(size 1.27 1.27)
				)
				(justify mirror)
			)
		)
		(property "Value" ""
			(at 0 0 0)
			(layer "B.Fab")
			(effects
				(font
					(size 1.27 1.27)
				)
				(justify mirror)
			)
		)
		(duplicate_pad_numbers_are_jumpers no)
		(fp_line
			(start -0.299974 -0.150114)
			(end -0.299974 0.150114)
			(stroke
				(width 0.1)
				(type default)
			)
			(layer "B.Fab")
		)
		(fp_line
			(start -0.299974 0.150114)
			(end 0.299974 0.150114)
			(stroke
				(width 0.1)
				(type default)
			)
			(layer "B.Fab")
		)
		(fp_line
			(start 0.299974 -0.150114)
			(end -0.299974 -0.150114)
			(stroke
				(width 0.1)
				(type default)
			)
			(layer "B.Fab")
		)
		(fp_line
			(start 0.299974 0.150114)
			(end 0.299974 -0.150114)
			(stroke
				(width 0.1)
				(type default)
			)
			(layer "B.Fab")
		)
		(pad "1" smd rect
			(at 0.2667 0 180)
			(size 0.3048 0.381)
			(layers "B.Cu" "B.Mask" "B.Paste")
			(net "PCEPLL1_VDDA18_PEX2")
		)
		(pad "2" smd rect
			(at -0.2667 0 180)
			(size 0.3048 0.381)
			(layers "B.Cu" "B.Mask" "B.Paste")
			(net "GND")
		)
	)
	(footprint ""
		(layer "B.Cu")
		(at 72.949816 -293.99992 180)
		(property "Reference" "C2950"
			(at 0 0 0)
			(layer "B.SilkS")
			(hide yes)
			(effects
				(font
					(size 1.27 1.27)
				)
				(justify mirror)
			)
		)
		(property "Value" ""
			(at 0 0 0)
			(layer "B.Fab")
			(effects
				(font
					(size 1.27 1.27)
				)
				(justify mirror)
			)
		)
		(duplicate_pad_numbers_are_jumpers no)
		(fp_line
			(start 0.299974 0.150114)
			(end 0.299974 -0.150114)
			(stroke
				(width 0.1)
				(type default)
			)
			(layer "B.Fab")
		)
		(fp_line
			(start 0.299974 -0.150114)
			(end -0.299974 -0.150114)
			(stroke
				(width 0.1)
				(type default)
			)
			(layer "B.Fab")
		)
		(fp_line
			(start -0.299974 0.150114)
			(end 0.299974 0.150114)
			(stroke
				(width 0.1)
				(type default)
			)
			(layer "B.Fab")
		)
		(fp_line
			(start -0.299974 -0.150114)
			(end -0.299974 0.150114)
			(stroke
				(width 0.1)
				(type default)
			)
			(layer "B.Fab")
		)
		(pad "1" smd rect
			(at 0.2667 0)
			(size 0.3048 0.381)
			(layers "B.Cu" "B.Mask" "B.Paste")
			(net "P1V25_SERDES_VDDPLL_PEX0")
		)
		(pad "2" smd rect
			(at -0.2667 0)
			(size 0.3048 0.381)
			(layers "B.Cu" "B.Mask" "B.Paste")
			(net "GND")
		)
	)
)
